(kicad_pcb
	(version 20241229)
	(generator "pcbnew")
	(generator_version "9.0")
	(general
		(thickness 1.294)
		(legacy_teardrops no)
	)
	(paper "A3")
	(title_block
		(title "Kintex 410T devboard")
		(date "2024-04-03")
		(rev "1.1.2")
		(comment 9 "footprints 609-614 of 975")
	)
	(layers
		(0 "F.Cu" mixed)
		(4 "In1.Cu" power)
		(6 "In2.Cu" power)
		(8 "In3.Cu" mixed)
		(10 "In4.Cu" power)
		(12 "In5.Cu" mixed)
		(14 "In6.Cu" power)
		(16 "In7.Cu" mixed)
		(18 "In8.Cu" power)
		(2 "B.Cu" mixed)
		(9 "F.Adhes" user "F.Adhesive")
		(11 "B.Adhes" user "B.Adhesive")
		(13 "F.Paste" user)
		(15 "B.Paste" user)
		(5 "F.SilkS" user "F.Silkscreen")
		(7 "B.SilkS" user "B.Silkscreen")
		(1 "F.Mask" user)
		(3 "B.Mask" user)
		(17 "Dwgs.User" user "User.Drawings")
		(19 "Cmts.User" user "User.Comments")
		(21 "Eco1.User" user "User.Eco1")
		(23 "Eco2.User" user "User.Eco2")
		(25 "Edge.Cuts" user)
		(27 "Margin" user)
		(31 "F.CrtYd" user "F.Courtyard")
		(29 "B.CrtYd" user "B.Courtyard")
		(35 "F.Fab" user)
		(33 "B.Fab" user)
	)
	(footprint "antmicro-footprints:R_0402_1005Metric"
		(layer "B.Cu")
		(at 258.4 95.8 -90)
		(descr "Resistor SMD 0402")
		(tags "resistor SMD 0402")
		(property "Reference" "R358"
			(at -1.225 0.475 90)
			(layer "B.SilkS")
			(effects
				(font
					(size 0.7 0.7)
					(thickness 0.15)
				)
				(justify left bottom mirror)
			)
		)
		(property "Value" "R_100k_0402"
			(at 0 -1.4 90)
			(layer "B.Fab")
			(effects
				(font
					(size 0.7 0.7)
					(thickness 0.15)
				)
				(justify left bottom mirror)
			)
		)
		(property "Description" "SMD Chip Resistor, 100 kohm, ± 1%, 62.5 mW, 0402 [1005 Metric], Thick Film, General Purpose"
			(at 0 0 270)
			(layer "F.Fab")
			(hide yes)
			(effects
				(font
					(size 1.27 1.27)
					(thickness 0.15)
				)
			)
		)
		(property "Author" "Antmicro"
			(at 162.6 354.2 0)
			(layer "B.Fab")
			(hide yes)
			(effects
				(font
					(size 1 1)
					(thickness 0.15)
				)
				(justify mirror)
			)
		)
		(property "License" "Apache-2.0"
			(at 162.6 354.2 0)
			(layer "B.Fab")
			(hide yes)
			(effects
				(font
					(size 1 1)
					(thickness 0.15)
				)
				(justify mirror)
			)
		)
		(property "MPN" "CR0402-FX-1003GLF"
			(at 162.6 354.2 0)
			(layer "B.Fab")
			(hide yes)
			(effects
				(font
					(size 1 1)
					(thickness 0.15)
				)
				(justify mirror)
			)
		)
		(property "Manufacturer" "Bourns"
			(at 162.6 354.2 0)
			(layer "B.Fab")
			(hide yes)
			(effects
				(font
					(size 1 1)
					(thickness 0.15)
				)
				(justify mirror)
			)
		)
		(property "Tolerance" "1%"
			(at 162.6 354.2 0)
			(layer "B.Fab")
			(hide yes)
			(effects
				(font
					(size 1 1)
					(thickness 0.15)
				)
				(justify mirror)
			)
		)
		(property "Val" "100k"
			(at 162.6 354.2 0)
			(layer "B.Fab")
			(hide yes)
			(effects
				(font
					(size 1 1)
					(thickness 0.15)
				)
				(justify mirror)
			)
		)
		(sheetname "User GPIO + LED + button + DIP switch")
		(sheetfile "user-gpio.kicad_sch")
		(attr smd)
		(fp_rect
			(start -0.925 0.47)
			(end 0.925 -0.47)
			(stroke
				(width 0.05)
				(type default)
			)
			(fill no)
			(layer "B.CrtYd")
		)
		(fp_rect
			(start -0.5 0.25)
			(end 0.5 -0.25)
			(stroke
				(width 0.15)
				(type solid)
			)
			(fill no)
			(layer "B.Fab")
		)
		(pad "1" smd roundrect
			(at -0.48 0 270)
			(size 0.59 0.64)
			(layers "B.Cu" "B.Mask" "B.Paste")
			(roundrect_rratio 0.25)
			(net 1304 "/USER_IO.LED_GREEN5")
			(pintype "passive")
		)
		(pad "2" smd roundrect
			(at 0.48 0 270)
			(size 0.59 0.64)
			(layers "B.Cu" "B.Mask" "B.Paste")
			(roundrect_rratio 0.25)
			(net 1 "GND")
			(pintype "passive")
		)
	)
	(footprint "antmicro-footprints:R_0402_1005Metric"
		(layer "B.Cu")
		(at 198.991252 96.95 90)
		(descr "Resistor SMD 0402")
		(tags "resistor SMD 0402")
		(property "Reference" "R216"
			(at -3.35 0.383748 270)
			(layer "B.SilkS")
			(effects
				(font
					(size 0.7 0.7)
					(thickness 0.15)
				)
				(justify left bottom mirror)
			)
		)
		(property "Value" "R_2k2_0402"
			(at 0 -1.4 270)
			(layer "B.Fab")
			(effects
				(font
					(size 0.7 0.7)
					(thickness 0.15)
				)
				(justify left bottom mirror)
			)
		)
		(property "Description" "SMD Chip Resistor, 2.2 kohm, ± 1%, 62.5 mW, 0402 [1005 Metric], Thick Film, General Purpose"
			(at 0 0 90)
			(layer "F.Fab")
			(hide yes)
			(effects
				(font
					(size 1.27 1.27)
					(thickness 0.15)
				)
			)
		)
		(property "Author" "Antmicro"
			(at 295.941252 -102.041252 0)
			(layer "B.Fab")
			(hide yes)
			(effects
				(font
					(size 1 1)
					(thickness 0.15)
				)
				(justify mirror)
			)
		)
		(property "DNP" "DNP"
			(at 295.941252 -102.041252 0)
			(layer "B.Fab")
			(hide yes)
			(effects
				(font
					(size 1 1)
					(thickness 0.15)
				)
				(justify mirror)
			)
		)
		(property "License" "Apache-2.0"
			(at 295.941252 -102.041252 0)
			(layer "B.Fab")
			(hide yes)
			(effects
				(font
					(size 1 1)
					(thickness 0.15)
				)
				(justify mirror)
			)
		)
		(property "MPN" "CR0402-FX-2201GLF"
			(at 295.941252 -102.041252 0)
			(layer "B.Fab")
			(hide yes)
			(effects
				(font
					(size 1 1)
					(thickness 0.15)
				)
				(justify mirror)
			)
		)
		(property "Manufacturer" "Bourns"
			(at 295.941252 -102.041252 0)
			(layer "B.Fab")
			(hide yes)
			(effects
				(font
					(size 1 1)
					(thickness 0.15)
				)
				(justify mirror)
			)
		)
		(property "Tolerance" "1%"
			(at 295.941252 -102.041252 0)
			(layer "B.Fab")
			(hide yes)
			(effects
				(font
					(size 1 1)
					(thickness 0.15)
				)
				(justify mirror)
			)
		)
		(property "Val" "2k2"
			(at 295.941252 -102.041252 0)
			(layer "B.Fab")
			(hide yes)
			(effects
				(font
					(size 1 1)
					(thickness 0.15)
				)
				(justify mirror)
			)
		)
		(property "dnp" ""
			(at 295.941252 -102.041252 0)
			(layer "B.Fab")
			(hide yes)
			(effects
				(font
					(size 1 1)
					(thickness 0.15)
				)
				(justify mirror)
			)
		)
		(property "exclude_from_bom" ""
			(at 295.941252 -102.041252 0)
			(layer "B.Fab")
			(hide yes)
			(effects
				(font
					(size 1 1)
					(thickness 0.15)
				)
				(justify mirror)
			)
		)
		(sheetname "HDMI + Ethernet")
		(sheetfile "hdmi-ethernet.kicad_sch")
		(attr smd exclude_from_bom)
		(fp_rect
			(start -0.925 0.47)
			(end 0.925 -0.47)
			(stroke
				(width 0.05)
				(type default)
			)
			(fill no)
			(layer "B.CrtYd")
		)
		(fp_rect
			(start -0.5 0.25)
			(end 0.5 -0.25)
			(stroke
				(width 0.15)
				(type solid)
			)
			(fill no)
			(layer "B.Fab")
		)
		(pad "1" smd roundrect
			(at -0.48 0 90)
			(size 0.59 0.64)
			(layers "B.Cu" "B.Mask" "B.Paste")
			(roundrect_rratio 0.25)
			(net 508 "/FPGA Bank 16 & 17/GBE_RGMII.~{INT}")
			(pintype "passive")
		)
		(pad "2" smd roundrect
			(at 0.48 0 90)
			(size 0.59 0.64)
			(layers "B.Cu" "B.Mask" "B.Paste")
			(roundrect_rratio 0.25)
			(net 1 "GND")
			(pintype "passive")
		)
	)
	(footprint "antmicro-footprints:C_0402_1005Metric"
		(layer "B.Cu")
		(at 252.501 161.6 -90)
		(descr "Capacitor SMD 0402")
		(tags "capacitor SMD 0402")
		(property "Reference" "C276"
			(at -1.375 -5.924 90)
			(layer "B.SilkS")
			(effects
				(font
					(size 0.7 0.7)
					(thickness 0.15)
				)
				(justify left bottom mirror)
			)
		)
		(property "Value" "C_10p_0402"
			(at 0 -1.4 90)
			(layer "B.Fab")
			(effects
				(font
					(size 0.7 0.7)
					(thickness 0.15)
				)
				(justify left bottom mirror)
			)
		)
		(property "Description" "SMD Multilayer Ceramic Capacitor, 10 pF, 50 V, 0402 [1005 Metric], ± 2%, C0G / NP0, GCM"
			(at 0 0 270)
			(layer "F.Fab")
			(hide yes)
			(effects
				(font
					(size 1.27 1.27)
					(thickness 0.15)
				)
			)
		)
		(property "Author" "Antmicro"
			(at 90.901 414.101 0)
			(layer "B.Fab")
			(hide yes)
			(effects
				(font
					(size 1 1)
					(thickness 0.15)
				)
				(justify mirror)
			)
		)
		(property "Dielectric" "C0G"
			(at 90.901 414.101 0)
			(layer "B.Fab")
			(hide yes)
			(effects
				(font
					(size 1 1)
					(thickness 0.15)
				)
				(justify mirror)
			)
		)
		(property "License" "Apache-2.0"
			(at 90.901 414.101 0)
			(layer "B.Fab")
			(hide yes)
			(effects
				(font
					(size 1 1)
					(thickness 0.15)
				)
				(justify mirror)
			)
		)
		(property "MPN" "GCM1555C1H100GA16D"
			(at 90.901 414.101 0)
			(layer "B.Fab")
			(hide yes)
			(effects
				(font
					(size 1 1)
					(thickness 0.15)
				)
				(justify mirror)
			)
		)
		(property "Manufacturer" "Murata"
			(at 90.901 414.101 0)
			(layer "B.Fab")
			(hide yes)
			(effects
				(font
					(size 1 1)
					(thickness 0.15)
				)
				(justify mirror)
			)
		)
		(property "Val" "10p"
			(at 90.901 414.101 0)
			(layer "B.Fab")
			(hide yes)
			(effects
				(font
					(size 1 1)
					(thickness 0.15)
				)
				(justify mirror)
			)
		)
		(property "Voltage" "50V"
			(at 90.901 414.101 0)
			(layer "B.Fab")
			(hide yes)
			(effects
				(font
					(size 1 1)
					(thickness 0.15)
				)
				(justify mirror)
			)
		)
		(sheetname "HDMI + Ethernet")
		(sheetfile "hdmi-ethernet.kicad_sch")
		(attr smd)
		(fp_rect
			(start -0.925 0.47)
			(end 0.925 -0.47)
			(stroke
				(width 0.05)
				(type default)
			)
			(fill no)
			(layer "B.CrtYd")
		)
		(fp_line
			(start -0.494 0.25)
			(end 0.504 0.25)
			(stroke
				(width 0.15)
				(type solid)
			)
			(layer "B.Fab")
		)
		(fp_line
			(start 0.504 0.25)
			(end 0.504 -0.248)
			(stroke
				(width 0.15)
				(type solid)
			)
			(layer "B.Fab")
		)
		(fp_line
			(start -0.494 -0.248)
			(end -0.494 0.25)
			(stroke
				(width 0.15)
				(type solid)
			)
			(layer "B.Fab")
		)
		(fp_line
			(start 0.504 -0.248)
			(end -0.494 -0.248)
			(stroke
				(width 0.15)
				(type solid)
			)
			(layer "B.Fab")
		)
		(pad "1" smd roundrect
			(at -0.48 0 270)
			(size 0.59 0.64)
			(layers "B.Cu" "B.Mask" "B.Paste")
			(roundrect_rratio 0.25)
			(net 1 "GND")
			(pintype "passive")
		)
		(pad "2" smd roundrect
			(at 0.48 0 270)
			(size 0.59 0.64)
			(layers "B.Cu" "B.Mask" "B.Paste")
			(roundrect_rratio 0.25)
			(net 726 "/HDMI + Ethernet/ETH2_P")
			(pintype "passive")
		)
	)
	(footprint "antmicro-footprints:R_0402_1005Metric"
		(layer "B.Cu")
		(at 247.401 130.1 90)
		(descr "Resistor SMD 0402")
		(tags "resistor SMD 0402")
		(property "Reference" "R91"
			(at -0.8 0.374 270)
			(layer "B.SilkS")
			(effects
				(font
					(size 0.7 0.7)
					(thickness 0.15)
				)
				(justify left bottom mirror)
			)
		)
		(property "Value" "R_10k_0402"
			(at 0 -1.4 270)
			(layer "B.Fab")
			(effects
				(font
					(size 0.7 0.7)
					(thickness 0.15)
				)
				(justify left bottom mirror)
			)
		)
		(property "Description" "SMD Chip Resistor, 10 kohm, ± 1%, 62.5 mW, 0402 [1005 Metric], Thick Film, General Purpose"
			(at 0 0 90)
			(layer "F.Fab")
			(hide yes)
			(effects
				(font
					(size 1.27 1.27)
					(thickness 0.15)
				)
			)
		)
		(property "Author" "Antmicro"
			(at 377.501 -117.301 0)
			(layer "B.Fab")
			(hide yes)
			(effects
				(font
					(size 1 1)
					(thickness 0.15)
				)
				(justify mirror)
			)
		)
		(property "License" "Apache-2.0"
			(at 377.501 -117.301 0)
			(layer "B.Fab")
			(hide yes)
			(effects
				(font
					(size 1 1)
					(thickness 0.15)
				)
				(justify mirror)
			)
		)
		(property "MPN" "CR0402-FX-1002GLF"
			(at 377.501 -117.301 0)
			(layer "B.Fab")
			(hide yes)
			(effects
				(font
					(size 1 1)
					(thickness 0.15)
				)
				(justify mirror)
			)
		)
		(property "Manufacturer" "Bourns"
			(at 377.501 -117.301 0)
			(layer "B.Fab")
			(hide yes)
			(effects
				(font
					(size 1 1)
					(thickness 0.15)
				)
				(justify mirror)
			)
		)
		(property "Tolerance" "1%"
			(at 377.501 -117.301 0)
			(layer "B.Fab")
			(hide yes)
			(effects
				(font
					(size 1 1)
					(thickness 0.15)
				)
				(justify mirror)
			)
		)
		(property "Val" "10k"
			(at 377.501 -117.301 0)
			(layer "B.Fab")
			(hide yes)
			(effects
				(font
					(size 1 1)
					(thickness 0.15)
				)
				(justify mirror)
			)
		)
		(sheetname "SPI Flash + SD Card")
		(sheetfile "spi-flash.kicad_sch")
		(attr smd)
		(fp_rect
			(start -0.925 0.47)
			(end 0.925 -0.47)
			(stroke
				(width 0.05)
				(type default)
			)
			(fill no)
			(layer "B.CrtYd")
		)
		(fp_rect
			(start -0.5 0.25)
			(end 0.5 -0.25)
			(stroke
				(width 0.15)
				(type solid)
			)
			(fill no)
			(layer "B.Fab")
		)
		(pad "1" smd roundrect
			(at -0.48 0 90)
			(size 0.59 0.64)
			(layers "B.Cu" "B.Mask" "B.Paste")
			(roundrect_rratio 0.25)
			(net 397 "/FPGA Bank 33 & 34/SD_CARD.DAT1")
			(pintype "passive")
		)
		(pad "2" smd roundrect
			(at 0.48 0 90)
			(size 0.59 0.64)
			(layers "B.Cu" "B.Mask" "B.Paste")
			(roundrect_rratio 0.25)
			(net 24 "+3V3")
			(pintype "passive")
		)
	)
	(footprint "antmicro-footprints:C_0402_1005Metric"
		(layer "B.Cu")
		(at 211.5 136 -90)
		(descr "Capacitor SMD 0402")
		(tags "capacitor SMD 0402")
		(property "Reference" "C36"
			(at -1.15 -1.275 90)
			(layer "B.SilkS")
			(effects
				(font
					(size 0.7 0.7)
					(thickness 0.15)
				)
				(justify left bottom mirror)
			)
		)
		(property "Value" "C_100n_0402"
			(at 0 -1.169 90)
			(layer "B.Fab")
			(effects
				(font
					(size 0.7 0.7)
					(thickness 0.15)
				)
				(justify left bottom mirror)
			)
		)
		(property "Description" "SMD Multilayer Ceramic Capacitor, 0.1 µF, 50 V, 0402 [1005 Metric], ± 10%, X5R, GRM Series"
			(at 0 0 270)
			(layer "F.Fab")
			(hide yes)
			(effects
				(font
					(size 1.27 1.27)
					(thickness 0.15)
				)
			)
		)
		(property "Author" "Antmicro"
			(at 75.5 347.5 0)
			(layer "B.Fab")
			(hide yes)
			(effects
				(font
					(size 1 1)
					(thickness 0.15)
				)
				(justify mirror)
			)
		)
		(property "Dielectric" "X5R"
			(at 75.5 347.5 0)
			(layer "B.Fab")
			(hide yes)
			(effects
				(font
					(size 1 1)
					(thickness 0.15)
				)
				(justify mirror)
			)
		)
		(property "License" "Apache-2.0"
			(at 75.5 347.5 0)
			(layer "B.Fab")
			(hide yes)
			(effects
				(font
					(size 1 1)
					(thickness 0.15)
				)
				(justify mirror)
			)
		)
		(property "MPN" "GRM155R61H104KE14D"
			(at 75.5 347.5 0)
			(layer "B.Fab")
			(hide yes)
			(effects
				(font
					(size 1 1)
					(thickness 0.15)
				)
				(justify mirror)
			)
		)
		(property "Manufacturer" "Murata"
			(at 75.5 347.5 0)
			(layer "B.Fab")
			(hide yes)
			(effects
				(font
					(size 1 1)
					(thickness 0.15)
				)
				(justify mirror)
			)
		)
		(property "Val" "100n"
			(at 75.5 347.5 0)
			(layer "B.Fab")
			(hide yes)
			(effects
				(font
					(size 1 1)
					(thickness 0.15)
				)
				(justify mirror)
			)
		)
		(property "Voltage" "50V"
			(at 75.5 347.5 0)
			(layer "B.Fab")
			(hide yes)
			(effects
				(font
					(size 1 1)
					(thickness 0.15)
				)
				(justify mirror)
			)
		)
		(sheetname "FPGA Bank 12 & 13")
		(sheetfile "fpga-bank-12-13.kicad_sch")
		(attr smd)
		(fp_rect
			(start -0.925 0.47)
			(end 0.925 -0.47)
			(stroke
				(width 0.05)
				(type default)
			)
			(fill no)
			(layer "B.CrtYd")
		)
		(fp_line
			(start -0.494 0.25)
			(end 0.504 0.25)
			(stroke
				(width 0.15)
				(type solid)
			)
			(layer "B.Fab")
		)
		(fp_line
			(start 0.504 0.25)
			(end 0.504 -0.248)
			(stroke
				(width 0.15)
				(type solid)
			)
			(layer "B.Fab")
		)
		(fp_line
			(start -0.494 -0.248)
			(end -0.494 0.25)
			(stroke
				(width 0.15)
				(type solid)
			)
			(layer "B.Fab")
		)
		(fp_line
			(start 0.504 -0.248)
			(end -0.494 -0.248)
			(stroke
				(width 0.15)
				(type solid)
			)
			(layer "B.Fab")
		)
		(pad "1" smd roundrect
			(at -0.48 0 270)
			(size 0.59 0.64)
			(layers "B.Cu" "B.Mask" "B.Paste")
			(roundrect_rratio 0.25)
			(net 1 "GND")
			(pintype "passive")
		)
		(pad "2" smd roundrect
			(at 0.48 0 270)
			(size 0.59 0.64)
			(layers "B.Cu" "B.Mask" "B.Paste")
			(roundrect_rratio 0.25)
			(net 24 "+3V3")
			(pintype "passive")
		)
	)
	(footprint "antmicro-footprints:C_1206_3216Metric"
		(layer "B.Cu")
		(at 163.360401 128.826401)
		(descr "Capacitor SMD 1206")
		(tags "capacitor SMD 1206")
		(property "Reference" "C297"
			(at -1.410401 2.023599 0)
			(layer "B.SilkS")
			(effects
				(font
					(size 0.7 0.7)
					(thickness 0.15)
				)
				(justify right bottom mirror)
			)
		)
		(property "Value" "C_47u_16V_1206"
			(at 0 -2.1 0)
			(layer "B.Fab")
			(effects
				(font
					(size 0.7 0.7)
					(thickness 0.15)
				)
				(justify right bottom mirror)
			)
		)
		(property "Description" "SMD Multilayer Ceramic Capacitor, 47 µF, 16 V, 1206 [3216 Metric], ± 20%, X5R, C"
			(at 0 0 0)
			(layer "F.Fab")
			(hide yes)
			(effects
				(font
					(size 1.27 1.27)
					(thickness 0.15)
				)
			)
		)
		(property "Author" "Antmicro"
			(at 0 0 0)
			(layer "B.Fab")
			(hide yes)
			(effects
				(font
					(size 1 1)
					(thickness 0.15)
				)
				(justify mirror)
			)
		)
		(property "Dielectric" "X5R"
			(at 0 0 0)
			(layer "B.Fab")
			(hide yes)
			(effects
				(font
					(size 1 1)
					(thickness 0.15)
				)
				(justify mirror)
			)
		)
		(property "License" "Apache-2.0"
			(at 0 0 0)
			(layer "B.Fab")
			(hide yes)
			(effects
				(font
					(size 1 1)
					(thickness 0.15)
				)
				(justify mirror)
			)
		)
		(property "MPN" "C3216X5R1C476M160AB"
			(at 0 0 0)
			(layer "B.Fab")
			(hide yes)
			(effects
				(font
					(size 1 1)
					(thickness 0.15)
				)
				(justify mirror)
			)
		)
		(property "Manufacturer" "TDK"
			(at 0 0 0)
			(layer "B.Fab")
			(hide yes)
			(effects
				(font
					(size 1 1)
					(thickness 0.15)
				)
				(justify mirror)
			)
		)
		(property "Val" "47u"
			(at 0 0 0)
			(layer "B.Fab")
			(hide yes)
			(effects
				(font
					(size 1 1)
					(thickness 0.15)
				)
				(justify mirror)
			)
		)
		(property "Voltage" "16V"
			(at 0 0 0)
			(layer "B.Fab")
			(hide yes)
			(effects
				(font
					(size 1 1)
					(thickness 0.15)
				)
				(justify mirror)
			)
		)
		(sheetname "FMC+ HSPC")
		(sheetfile "fmc-hspc.kicad_sch")
		(attr smd)
		(fp_line
			(start 0.8 -0.901)
			(end -0.8 -0.901)
			(stroke
				(width 0.15)
				(type solid)
			)
			(layer "B.SilkS")
		)
		(fp_line
			(start 0.8 0.899)
			(end -0.8 0.899)
			(stroke
				(width 0.15)
				(type solid)
			)
			(layer "B.SilkS")
		)
		(fp_rect
			(start -2.325 1.15)
			(end 2.325 -1.15)
			(stroke
				(width 0.05)
				(type default)
			)
			(fill no)
			(layer "B.CrtYd")
		)
		(fp_rect
			(start -1.6 0.799)
			(end 1.6 -0.801)
			(stroke
				(width 0.15)
				(type solid)
			)
			(fill no)
			(layer "B.Fab")
		)
		(pad "1" smd roundrect
			(at -1.5 -0.001)
			(size 1.15 1.8)
			(layers "B.Cu" "B.Mask" "B.Paste")
			(roundrect_rratio 0.25)
			(net 1 "GND")
			(pintype "passive")
		)
		(pad "2" smd roundrect
			(at 1.5 -0.001)
			(size 1.15 1.8)
			(layers "B.Cu" "B.Mask" "B.Paste")
			(roundrect_rratio 0.25)
			(net 59 "12P0V")
			(pintype "passive")
		)
	)
)
